(kicad_pcb
	(version 20260206)
	(generator "pcbnew")
	(generator_version "10.0")
	(general
		(thickness 1.6)
		(legacy_teardrops no)
	)
	(paper "A4")
	(title_block
		(title "Bryce Canyon_F.DPB_16315-1-OCP.brd")
		(comment 1 "Bryce Canyon / footprints 1593-1600 of 2223")
	)
	(layers
		(0 "F.Cu" signal "TOP")
		(4 "In1.Cu" signal "L2GND")
		(6 "In2.Cu" signal "L3")
		(8 "In3.Cu" signal "L4GND")
		(10 "In4.Cu" signal "L5")
		(12 "In5.Cu" signal "L6VCC")
		(14 "In6.Cu" signal "L7VCC")
		(16 "In7.Cu" signal "L8")
		(18 "In8.Cu" signal "L9GND")
		(20 "In9.Cu" signal "L10")
		(22 "In10.Cu" signal "L11GND")
		(2 "B.Cu" signal "BOTTOM")
		(9 "F.Adhes" user "F.Adhesive")
		(11 "B.Adhes" user "B.Adhesive")
		(13 "F.Paste" user "Package Geometry/Pastemask Top")
		(15 "B.Paste" user "Package Geometry/Pastemask Bottom")
		(5 "F.SilkS" user "Ref Des/Silkscreen Top")
		(7 "B.SilkS" user "Ref Des/Silkscreen Bottom")
		(1 "F.Mask" user "Board Geometry/Soldermask Top")
		(3 "B.Mask" user "Board Geometry/Soldermask Bottom")
		(17 "Dwgs.User" user "User.Drawings")
		(19 "Cmts.User" user "User.Comments")
		(21 "Eco1.User" user "User.Eco1")
		(23 "Eco2.User" user "User.Eco2")
		(25 "Edge.Cuts" user "Board Geometry/Outline")
		(27 "Margin" user)
		(31 "F.CrtYd" user "Package Geometry/Place Bound Top")
		(29 "B.CrtYd" user "Package Geometry/Place Bound Bottom")
		(35 "F.Fab" user "Ref Des/Assembly Top")
		(33 "B.Fab" user "Ref Des/Assembly Bottom")
	)
	(footprint ""
		(layer "F.Cu")
		(at 224.553526 -136.293098 -90)
		(property "Reference" "TP211"
			(at 0 0 270)
			(layer "F.SilkS")
			(hide yes)
			(effects
				(font
					(size 1.27 1.27)
				)
			)
		)
		(property "Value" "TPAD32-GP"
			(at -0.0508 -1.6764 270)
			(unlocked yes)
			(layer "F.Fab")
			(hide yes)
			(effects
				(font
					(size 1.016 1.016)
					(thickness 0.1524)
				)
			)
		)
		(property "Device Type" "TPAD32"
			(at -0.0508 -3.2004 270)
			(unlocked yes)
			(layer "F.Fab")
			(hide yes)
			(effects
				(font
					(size 1.016 1.016)
					(thickness 0.1524)
				)
			)
		)
		(duplicate_pad_numbers_are_jumpers no)
		(fp_poly
			(pts
				(arc
					(start 0 -0.4064)
					(mid 0 0.4064)
					(end 0 -0.4064)
				)
			)
			(stroke
				(width 0)
				(type default)
			)
			(fill no)
			(layer "F.CrtYd")
		)
		(fp_poly
			(pts
				(arc
					(start 0 -0.7112)
					(mid 0 0.7112)
					(end 0 -0.7112)
				)
			)
			(stroke
				(width 0)
				(type default)
			)
			(fill no)
			(layer "F.Fab")
		)
		(pad "1" smd circle
			(at 0 0 270)
			(size 0.8128 0.8128)
			(layers "F.Cu" "F.Mask" "F.Paste")
			(net "TP_PCIE_COMP_A_CLK_1_DP")
		)
	)
	(footprint ""
		(layer "F.Cu")
		(at 161.880804 -187.468764)
		(property "Reference" "R473"
			(at 0 0 0)
			(layer "F.SilkS")
			(hide yes)
			(effects
				(font
					(size 1.27 1.27)
				)
			)
		)
		(property "Value" "4K7R2J-2-GP"
			(at 0.064008 -3.993896 0)
			(unlocked yes)
			(layer "F.Fab")
			(hide yes)
			(effects
				(font
					(size 1.016 1.016)
					(thickness 0.1524)
				)
			)
		)
		(property "Device Type" "R402H16"
			(at 0.064008 -5.517896 0)
			(unlocked yes)
			(layer "F.Fab")
			(hide yes)
			(effects
				(font
					(size 1.016 1.016)
					(thickness 0.1524)
				)
			)
		)
		(duplicate_pad_numbers_are_jumpers no)
		(fp_line
			(start -0.508 -0.9398)
			(end -0.508 0.9398)
			(stroke
				(width 0.1524)
				(type default)
			)
			(layer "F.SilkS")
		)
		(fp_line
			(start 0.508 -0.9398)
			(end -0.508 -0.9398)
			(stroke
				(width 0.1524)
				(type default)
			)
			(layer "F.SilkS")
		)
		(fp_rect
			(start -0.508 0.9398)
			(end 0.508 -0.9398)
			(stroke
				(width 0)
				(type default)
			)
			(fill no)
			(layer "F.CrtYd")
		)
		(fp_rect
			(start -0.508 0.9398)
			(end 0.508 -0.9398)
			(stroke
				(width 0)
				(type default)
			)
			(fill no)
			(layer "F.Fab")
		)
		(pad "1" smd custom
			(at 0 -0.4445)
			(size 0.1397 0.1397)
			(layers "F.Cu" "F.Mask" "F.Paste")
			(net "DRIVE_A_5_FLT_LED")
			(options
				(clearance outline)
				(anchor circle)
			)
			(primitives
				(gr_poly
					(pts
						(arc
							(start -0.1778 -0.2794)
							(mid -0.249642 -0.249642)
							(end -0.2794 -0.1778)
						)
						(arc
							(start -0.2794 0.1778)
							(mid -0.249642 0.249642)
							(end -0.1778 0.2794)
						)
						(arc
							(start 0.1778 0.2794)
							(mid 0.249642 0.249642)
							(end 0.2794 0.1778)
						)
						(arc
							(start 0.2794 -0.1778)
							(mid 0.249642 -0.249642)
							(end 0.1778 -0.2794)
						)
					)
					(width 0)
					(fill yes)
				)
			)
		)
		(pad "2" smd custom
			(at 0 0.4445)
			(size 0.1397 0.1397)
			(layers "F.Cu" "F.Mask" "F.Paste")
			(net "GND")
			(options
				(clearance outline)
				(anchor circle)
			)
			(primitives
				(gr_poly
					(pts
						(arc
							(start -0.1778 -0.2794)
							(mid -0.249642 -0.249642)
							(end -0.2794 -0.1778)
						)
						(arc
							(start -0.2794 0.1778)
							(mid -0.249642 0.249642)
							(end -0.1778 0.2794)
						)
						(arc
							(start 0.1778 0.2794)
							(mid 0.249642 0.249642)
							(end 0.2794 0.1778)
						)
						(arc
							(start 0.2794 -0.1778)
							(mid 0.249642 -0.249642)
							(end 0.1778 -0.2794)
						)
					)
					(width 0)
					(fill yes)
				)
			)
		)
	)
	(footprint ""
		(layer "F.Cu")
		(at 47.877476 -140.73505 -90)
		(property "Reference" "R1231"
			(at 0 0 270)
			(layer "F.SilkS")
			(hide yes)
			(effects
				(font
					(size 1.27 1.27)
				)
			)
		)
		(property "Value" "3D01R5F-GP"
			(at 0 -8.9535 270)
			(unlocked yes)
			(layer "F.Fab")
			(hide yes)
			(effects
				(font
					(size 1.27 1.016)
					(thickness 0.1524)
				)
			)
		)
		(property "Device Type" "R805H24"
			(at 0 -10.6299 270)
			(unlocked yes)
			(layer "F.Fab")
			(hide yes)
			(effects
				(font
					(size 1.27 1.016)
					(thickness 0.1524)
				)
			)
		)
		(duplicate_pad_numbers_are_jumpers no)
		(fp_line
			(start -0.889 1.7018)
			(end 0.889 1.7018)
			(stroke
				(width 0.1524)
				(type default)
			)
			(layer "F.SilkS")
		)
		(fp_line
			(start 0.889 1.7018)
			(end 0.889 -0.508)
			(stroke
				(width 0.1524)
				(type default)
			)
			(layer "F.SilkS")
		)
		(fp_line
			(start -0.889 0.0762)
			(end -0.889 1.7018)
			(stroke
				(width 0.1524)
				(type default)
			)
			(layer "F.SilkS")
		)
		(fp_line
			(start -0.889 -1.7018)
			(end -0.889 0.2794)
			(stroke
				(width 0.1524)
				(type default)
			)
			(layer "F.SilkS")
		)
		(fp_line
			(start 0.889 -1.7018)
			(end 0.889 -0.381)
			(stroke
				(width 0.1524)
				(type default)
			)
			(layer "F.SilkS")
		)
		(fp_line
			(start 0.889 -1.7018)
			(end -0.889 -1.7018)
			(stroke
				(width 0.1524)
				(type default)
			)
			(layer "F.SilkS")
		)
		(fp_poly
			(pts
				(xy 0.9652 -1.778) (xy 0.9652 1.778) (xy -0.9652 1.778) (xy -0.9652 -1.778)
			)
			(stroke
				(width 0)
				(type default)
			)
			(fill no)
			(layer "F.CrtYd")
		)
		(fp_rect
			(start -0.9652 1.778)
			(end 0.9652 -1.778)
			(stroke
				(width 0)
				(type default)
			)
			(fill no)
			(layer "F.Fab")
		)
		(pad "1" smd rect
			(at 0 -0.9652 270)
			(size 1.397 1.143)
			(layers "F.Cu" "F.Mask" "F.Paste")
			(net "P5V_B_SNB")
		)
		(pad "2" smd rect
			(at 0 0.9652 270)
			(size 1.397 1.143)
			(layers "F.Cu" "F.Mask" "F.Paste")
			(net "GND")
		)
	)
	(footprint ""
		(layer "F.Cu")
		(at 321.634612 -158.660592 -90)
		(property "Reference" "C273"
			(at 0 0 270)
			(layer "F.SilkS")
			(hide yes)
			(effects
				(font
					(size 1.27 1.27)
				)
			)
		)
		(property "Value" "SCD01U16V1KX-GP"
			(at -2.8321 -1.7399 270)
			(unlocked yes)
			(layer "F.Fab")
			(hide yes)
			(effects
				(font
					(size 1.016 1.016)
					(thickness 0.1524)
				)
			)
		)
		(property "Device Type" "C0201H13"
			(at -2.8321 -3.2639 270)
			(unlocked yes)
			(layer "F.Fab")
			(hide yes)
			(effects
				(font
					(size 1.016 1.016)
					(thickness 0.1524)
				)
			)
		)
		(duplicate_pad_numbers_are_jumpers no)
		(fp_rect
			(start -0.2794 0.6477)
			(end 0.2794 -0.6477)
			(stroke
				(width 0)
				(type default)
			)
			(fill no)
			(layer "F.CrtYd")
		)
		(fp_rect
			(start -0.2794 0.6477)
			(end 0.2794 -0.6477)
			(stroke
				(width 0)
				(type default)
			)
			(fill no)
			(layer "F.Fab")
		)
		(pad "1" smd custom
			(at 0 -0.2794 270)
			(size 0.0762 0.0762)
			(layers "F.Cu" "F.Mask" "F.Paste")
			(net "SAS_HDD_RX_P18")
			(options
				(clearance outline)
				(anchor circle)
			)
			(primitives
				(gr_poly
					(pts
						(arc
							(start 0.1524 -0.127)
							(mid 0.137521 -0.162921)
							(end 0.1016 -0.1778)
						)
						(arc
							(start -0.1016 -0.1778)
							(mid -0.137521 -0.162921)
							(end -0.1524 -0.127)
						)
						(arc
							(start -0.1524 0.127)
							(mid -0.137521 0.162921)
							(end -0.1016 0.1778)
						)
						(arc
							(start 0.1016 0.1778)
							(mid 0.137521 0.162921)
							(end 0.1524 0.127)
						)
					)
					(width 0)
					(fill yes)
				)
			)
		)
		(pad "2" smd custom
			(at 0 0.2794 270)
			(size 0.0762 0.0762)
			(layers "F.Cu" "F.Mask" "F.Paste")
			(net "PHY_SCC_A_TO_DRV_A_18_DP")
			(options
				(clearance outline)
				(anchor circle)
			)
			(primitives
				(gr_poly
					(pts
						(arc
							(start 0.1524 -0.127)
							(mid 0.137521 -0.162921)
							(end 0.1016 -0.1778)
						)
						(arc
							(start -0.1016 -0.1778)
							(mid -0.137521 -0.162921)
							(end -0.1524 -0.127)
						)
						(arc
							(start -0.1524 0.127)
							(mid -0.137521 0.162921)
							(end -0.1016 0.1778)
						)
						(arc
							(start 0.1016 0.1778)
							(mid 0.137521 0.162921)
							(end 0.1524 0.127)
						)
					)
					(width 0)
					(fill yes)
				)
			)
		)
	)
	(footprint ""
		(layer "F.Cu")
		(at 395.20495 -272.585942)
		(property "Reference" "R327"
			(at 0 0 0)
			(layer "F.SilkS")
			(hide yes)
			(effects
				(font
					(size 1.27 1.27)
				)
			)
		)
		(property "Value" "4K7R2J-2-GP"
			(at 0.064008 -3.993896 0)
			(unlocked yes)
			(layer "F.Fab")
			(hide yes)
			(effects
				(font
					(size 1.016 1.016)
					(thickness 0.1524)
				)
			)
		)
		(property "Device Type" "R402H16"
			(at 0.064008 -5.517896 0)
			(unlocked yes)
			(layer "F.Fab")
			(hide yes)
			(effects
				(font
					(size 1.016 1.016)
					(thickness 0.1524)
				)
			)
		)
		(duplicate_pad_numbers_are_jumpers no)
		(fp_line
			(start -0.508 -0.9398)
			(end -0.508 0.9398)
			(stroke
				(width 0.1524)
				(type default)
			)
			(layer "F.SilkS")
		)
		(fp_line
			(start 0.508 -0.9398)
			(end -0.508 -0.9398)
			(stroke
				(width 0.1524)
				(type default)
			)
			(layer "F.SilkS")
		)
		(fp_rect
			(start -0.508 0.9398)
			(end 0.508 -0.9398)
			(stroke
				(width 0)
				(type default)
			)
			(fill no)
			(layer "F.CrtYd")
		)
		(fp_rect
			(start -0.508 0.9398)
			(end 0.508 -0.9398)
			(stroke
				(width 0)
				(type default)
			)
			(fill no)
			(layer "F.Fab")
		)
		(pad "1" smd custom
			(at 0 -0.4445)
			(size 0.1397 0.1397)
			(layers "F.Cu" "F.Mask" "F.Paste")
			(net "SW_PWR_R_HDD8")
			(options
				(clearance outline)
				(anchor circle)
			)
			(primitives
				(gr_poly
					(pts
						(arc
							(start -0.1778 -0.2794)
							(mid -0.249642 -0.249642)
							(end -0.2794 -0.1778)
						)
						(arc
							(start -0.2794 0.1778)
							(mid -0.249642 0.249642)
							(end -0.1778 0.2794)
						)
						(arc
							(start 0.1778 0.2794)
							(mid 0.249642 0.249642)
							(end 0.2794 0.1778)
						)
						(arc
							(start 0.2794 -0.1778)
							(mid 0.249642 -0.249642)
							(end 0.1778 -0.2794)
						)
					)
					(width 0)
					(fill yes)
				)
			)
		)
		(pad "2" smd custom
			(at 0 0.4445)
			(size 0.1397 0.1397)
			(layers "F.Cu" "F.Mask" "F.Paste")
			(net "GND")
			(options
				(clearance outline)
				(anchor circle)
			)
			(primitives
				(gr_poly
					(pts
						(arc
							(start -0.1778 -0.2794)
							(mid -0.249642 -0.249642)
							(end -0.2794 -0.1778)
						)
						(arc
							(start -0.2794 0.1778)
							(mid -0.249642 0.249642)
							(end -0.1778 0.2794)
						)
						(arc
							(start 0.1778 0.2794)
							(mid 0.249642 0.249642)
							(end 0.2794 0.1778)
						)
						(arc
							(start 0.2794 -0.1778)
							(mid 0.249642 -0.249642)
							(end 0.1778 -0.2794)
						)
					)
					(width 0)
					(fill yes)
				)
			)
		)
	)
	(footprint ""
		(layer "F.Cu")
		(at 67.347846 -291.127942 90)
		(property "Reference" "C55"
			(at 0 0 90)
			(layer "F.SilkS")
			(hide yes)
			(effects
				(font
					(size 1.27 1.27)
				)
			)
		)
		(property "Value" "SCD01U50V2KX-1GP"
			(at 1.1811 -2.7051 90)
			(unlocked yes)
			(layer "F.Fab")
			(hide yes)
			(effects
				(font
					(size 1.016 1.016)
					(thickness 0.1524)
				)
			)
		)
		(property "Device Type" "C402H22"
			(at 1.1811 -4.2291 90)
			(unlocked yes)
			(layer "F.Fab")
			(hide yes)
			(effects
				(font
					(size 1.016 1.016)
					(thickness 0.1524)
				)
			)
		)
		(duplicate_pad_numbers_are_jumpers no)
		(fp_rect
			(start -0.4318 0.9525)
			(end 0.4318 -0.9525)
			(stroke
				(width 0)
				(type default)
			)
			(fill no)
			(layer "F.CrtYd")
		)
		(fp_rect
			(start -0.4318 0.9525)
			(end 0.4318 -0.9525)
			(stroke
				(width 0)
				(type default)
			)
			(fill no)
			(layer "F.Fab")
		)
		(pad "1" smd custom
			(at 0 -0.4445 90)
			(size 0.1524 0.1524)
			(layers "F.Cu" "F.Mask" "F.Paste")
			(net "HDD_PRSNT_1")
			(options
				(clearance outline)
				(anchor circle)
			)
			(primitives
				(gr_poly
					(pts
						(arc
							(start 0.3048 -0.2032)
							(mid 0.275042 -0.275042)
							(end 0.2032 -0.3048)
						)
						(arc
							(start -0.2032 -0.3048)
							(mid -0.275042 -0.275042)
							(end -0.3048 -0.2032)
						)
						(arc
							(start -0.3048 0.2032)
							(mid -0.275042 0.275042)
							(end -0.2032 0.3048)
						)
						(arc
							(start 0.2032 0.3048)
							(mid 0.275042 0.275042)
							(end 0.3048 0.2032)
						)
					)
					(width 0)
					(fill yes)
				)
			)
		)
		(pad "2" smd custom
			(at 0 0.4445 90)
			(size 0.1524 0.1524)
			(layers "F.Cu" "F.Mask" "F.Paste")
			(net "GND")
			(options
				(clearance outline)
				(anchor circle)
			)
			(primitives
				(gr_poly
					(pts
						(arc
							(start 0.3048 -0.2032)
							(mid 0.275042 -0.275042)
							(end 0.2032 -0.3048)
						)
						(arc
							(start -0.2032 -0.3048)
							(mid -0.275042 -0.275042)
							(end -0.3048 -0.2032)
						)
						(arc
							(start -0.3048 0.2032)
							(mid -0.275042 0.275042)
							(end -0.2032 0.3048)
						)
						(arc
							(start 0.2032 0.3048)
							(mid 0.275042 0.275042)
							(end 0.3048 0.2032)
						)
					)
					(width 0)
					(fill yes)
				)
			)
		)
	)
	(footprint ""
		(layer "F.Cu")
		(at 387.83895 -162.749992 -90)
		(property "Reference" "VIA26"
			(at 0 0 270)
			(layer "F.SilkS")
			(hide yes)
			(effects
				(font
					(size 1.27 1.27)
				)
			)
		)
		(property "Value" "100OHM-8L-1D6MM-L18L16-GP"
			(at -3.7211 -4.5085 270)
			(unlocked yes)
			(layer "F.Fab")
			(hide yes)
			(effects
				(font
					(size 1.016 1.016)
					(thickness 0.1524)
				)
			)
		)
		(property "Device Type" "VIA-PCIE-4P-394076"
			(at -3.7211 -6.0325 270)
			(unlocked yes)
			(layer "F.Fab")
			(hide yes)
			(effects
				(font
					(size 1.016 1.016)
					(thickness 0.1524)
				)
			)
		)
		(duplicate_pad_numbers_are_jumpers no)
		(fp_rect
			(start -1.9685 0.381)
			(end 1.9685 -0.381)
			(stroke
				(width 0)
				(type default)
			)
			(fill no)
			(layer "F.CrtYd")
		)
		(fp_rect
			(start -1.9685 0.381)
			(end 1.9685 -0.381)
			(stroke
				(width 0)
				(type default)
			)
			(fill no)
			(layer "F.Fab")
		)
		(pad "1" thru_hole circle
			(at -1.5875 0 270)
			(size 0.508 0.508)
			(drill 0.254)
			(layers "*.Cu" "*.Mask")
			(remove_unused_layers no)
			(net "GND")
			(clearance 0.127)
			(thermal_gap 0.127)
		)
		(pad "2" thru_hole circle
			(at -0.5715 0 270)
			(size 0.508 0.508)
			(drill 0.254)
			(layers "*.Cu" "*.Mask")
			(remove_unused_layers no)
			(net "PHY_DRV_A_TO_SCC_A_20_DP")
			(clearance 0.127)
			(thermal_gap 0.127)
		)
		(pad "3" thru_hole circle
			(at 0.5715 0 270)
			(size 0.508 0.508)
			(drill 0.254)
			(layers "*.Cu" "*.Mask")
			(remove_unused_layers no)
			(net "PHY_DRV_A_TO_SCC_A_20_DN")
			(clearance 0.127)
			(thermal_gap 0.127)
		)
		(pad "4" thru_hole circle
			(at 1.5875 0 270)
			(size 0.508 0.508)
			(drill 0.254)
			(layers "*.Cu" "*.Mask")
			(remove_unused_layers no)
			(net "GND")
			(clearance 0.127)
			(thermal_gap 0.127)
		)
	)
	(footprint ""
		(layer "F.Cu")
		(at 138.018266 -134.246874 -90)
		(property "Reference" "R1042"
			(at 0 0 270)
			(layer "F.SilkS")
			(hide yes)
			(effects
				(font
					(size 1.27 1.27)
				)
			)
		)
		(property "Value" "0R2J-2-GP"
			(at 0.064008 -3.993896 270)
			(unlocked yes)
			(layer "F.Fab")
			(hide yes)
			(effects
				(font
					(size 1.016 1.016)
					(thickness 0.1524)
				)
			)
		)
		(property "Device Type" "R402H16"
			(at 0.064008 -5.517896 270)
			(unlocked yes)
			(layer "F.Fab")
			(hide yes)
			(effects
				(font
					(size 1.016 1.016)
					(thickness 0.1524)
				)
			)
		)
		(duplicate_pad_numbers_are_jumpers no)
		(fp_line
			(start -0.508 -0.9398)
			(end -0.508 0.9398)
			(stroke
				(width 0.1524)
				(type default)
			)
			(layer "F.SilkS")
		)
		(fp_line
			(start 0.508 -0.9398)
			(end -0.508 -0.9398)
			(stroke
				(width 0.1524)
				(type default)
			)
			(layer "F.SilkS")
		)
		(fp_rect
			(start -0.508 0.9398)
			(end 0.508 -0.9398)
			(stroke
				(width 0)
				(type default)
			)
			(fill no)
			(layer "F.CrtYd")
		)
		(fp_rect
			(start -0.508 0.9398)
			(end 0.508 -0.9398)
			(stroke
				(width 0)
				(type default)
			)
			(fill no)
			(layer "F.Fab")
		)
		(pad "1" smd custom
			(at 0 -0.4445 270)
			(size 0.1397 0.1397)
			(layers "F.Cu" "F.Mask" "F.Paste")
			(net "MB0_SCL_R")
			(options
				(clearance outline)
				(anchor circle)
			)
			(primitives
				(gr_poly
					(pts
						(arc
							(start -0.1778 -0.2794)
							(mid -0.249642 -0.249642)
							(end -0.2794 -0.1778)
						)
						(arc
							(start -0.2794 0.1778)
							(mid -0.249642 0.249642)
							(end -0.1778 0.2794)
						)
						(arc
							(start 0.1778 0.2794)
							(mid 0.249642 0.249642)
							(end 0.2794 0.1778)
						)
						(arc
							(start 0.2794 -0.1778)
							(mid 0.249642 -0.249642)
							(end 0.1778 -0.2794)
						)
					)
					(width 0)
					(fill yes)
				)
			)
		)
		(pad "2" smd custom
			(at 0 0.4445 270)
			(size 0.1397 0.1397)
			(layers "F.Cu" "F.Mask" "F.Paste")
			(net "I2C_BMC_A_MISC_SCL")
			(options
				(clearance outline)
				(anchor circle)
			)
			(primitives
				(gr_poly
					(pts
						(arc
							(start -0.1778 -0.2794)
							(mid -0.249642 -0.249642)
							(end -0.2794 -0.1778)
						)
						(arc
							(start -0.2794 0.1778)
							(mid -0.249642 0.249642)
							(end -0.1778 0.2794)
						)
						(arc
							(start 0.1778 0.2794)
							(mid 0.249642 0.249642)
							(end 0.2794 0.1778)
						)
						(arc
							(start 0.2794 -0.1778)
							(mid 0.249642 -0.249642)
							(end 0.1778 -0.2794)
						)
					)
					(width 0)
					(fill yes)
				)
			)
		)
	)
)
